# TIMECARD (Time Appliance Project (Time Card)) — schematic netlist excerpt (pin names and nets, part order shuffled) for the footprints in the layout excerpt that follows; sources: Cadence DE-HDL packaged netlist, KiCad conversion of R4006-B0001-02_R01.brd

C129  CAPACITOR  0.1UF 10V 10%  pkg SMC_0402R_H022  page 14 : \1\ = XP1R0V_FPGA_VCCINT ; \2\ = SG
C36  CAPACITOR  0.1UF 10%  pkg SMC_0402R_H022  page 9 : \1\ = C_CPU_RX_PCIE_MGT3_TXN ; \2\ = CPU_RX_PCIE_MGT3_TXN

(kicad_pcb
	(version 20260206)
	(generator "pcbnew")
	(generator_version "10.0")
	(general
		(thickness 1.6)
		(legacy_teardrops no)
	)
	(paper "A4")
	(title_block
		(title "timecard-production-celestica-r4006 — R4006-B0001-02_R01.brd")
		(comment 1 "Time Appliance Project (Time Card) / footprints 1021-1022 of 1113")
	)
	(layers
		(0 "F.Cu" signal "TOP")
		(4 "In1.Cu" signal "L02_GND1")
		(6 "In2.Cu" signal "L03_SIG1")
		(8 "In3.Cu" signal "L04_GND2")
		(10 "In4.Cu" signal "L05_VCC1")
		(12 "In5.Cu" signal "L06_VCC2")
		(14 "In6.Cu" signal "L07_GND3")
		(16 "In7.Cu" signal "L08_SIG2")
		(18 "In8.Cu" signal "L09_GND4")
		(2 "B.Cu" signal "BOTTOM")
		(9 "F.Adhes" user "F.Adhesive")
		(11 "B.Adhes" user "B.Adhesive")
		(13 "F.Paste" user "Package Geometry/Pastemask Top")
		(15 "B.Paste" user "Package Geometry/Pastemask Bottom")
		(5 "F.SilkS" user "Ref Des/Silkscreen Top")
		(7 "B.SilkS" user "Ref Des/Silkscreen Bottom")
		(1 "F.Mask" user "Board Geometry/Soldermask Top")
		(3 "B.Mask" user "Board Geometry/Soldermask Bottom")
		(17 "Dwgs.User" user "User.Drawings")
		(19 "Cmts.User" user "User.Comments")
		(21 "Eco1.User" user "User.Eco1")
		(23 "Eco2.User" user "User.Eco2")
		(25 "Edge.Cuts" user "Board Geometry/Outline")
		(27 "Margin" user)
		(31 "F.CrtYd" user "Package Geometry/Place Bound Top")
		(29 "B.CrtYd" user "Package Geometry/Place Bound Bottom")
		(35 "F.Fab" user "Ref Des/Assembly Top")
		(33 "B.Fab" user "Ref Des/Assembly Bottom")
	)
	(footprint ""
		(layer "B.Cu")
		(at 110.847124 -41.32326 -90)
		(property "Reference" "C129"
			(at 0.81026 42.044874 270)
			(unlocked yes)
			(layer "B.SilkS")
			(effects
				(font
					(size 0.635 0.4064)
					(thickness 0.1524)
				)
				(justify mirror)
			)
		)
		(property "Value" "VAL*"
			(at 0 3.718306 270)
			(unlocked yes)
			(layer "B.Fab")
			(hide yes)
			(effects
				(font
					(size 0.7874 0.5842)
					(thickness 0.127)
				)
				(justify mirror)
			)
		)
		(property "Tolerance" "TOL*"
			(at 0 4.861306 270)
			(unlocked yes)
			(layer "Cmts.User")
			(hide yes)
			(effects
				(font
					(size 0.7874 0.5842)
					(thickness 0.127)
				)
				(justify mirror)
			)
		)
		(property "User Part Number" "PARTNUM*"
			(at 0 2.575306 270)
			(unlocked yes)
			(layer "Cmts.User")
			(hide yes)
			(effects
				(font
					(size 0.7874 0.5842)
					(thickness 0.127)
				)
				(justify mirror)
			)
		)
		(property "Device Type" "CAPACITOR-G105-0B104-CK,0.1UF,A"
			(at 0 1.432306 270)
			(unlocked yes)
			(layer "B.Fab")
			(hide yes)
			(effects
				(font
					(size 0.7874 0.5842)
					(thickness 0.127)
				)
				(justify mirror)
			)
		)
		(duplicate_pad_numbers_are_jumpers no)
		(fp_line
			(start -0.970026 0.4699)
			(end 0.970026 0.4699)
			(stroke
				(width 0.1)
				(type default)
			)
			(layer "B.SilkS")
		)
		(fp_line
			(start 0.970026 0.4699)
			(end 0.970026 -0.4699)
			(stroke
				(width 0.1)
				(type default)
			)
			(layer "B.SilkS")
		)
		(fp_line
			(start -0.970026 -0.4699)
			(end -0.970026 0.4699)
			(stroke
				(width 0.1)
				(type default)
			)
			(layer "B.SilkS")
		)
		(fp_line
			(start 0.970026 -0.4699)
			(end -0.970026 -0.4699)
			(stroke
				(width 0.1)
				(type default)
			)
			(layer "B.SilkS")
		)
		(fp_poly
			(pts
				(xy 0.970026 0.4699) (xy -0.970026 0.4699) (xy -0.970026 -0.4699) (xy 0.970026 -0.4699)
			)
			(stroke
				(width 0)
				(type default)
			)
			(fill no)
			(layer "B.CrtYd")
		)
		(fp_line
			(start -0.508 0.3048)
			(end 0.508 0.3048)
			(stroke
				(width 0.1)
				(type default)
			)
			(layer "B.Fab")
		)
		(fp_line
			(start 0.508 0.3048)
			(end 0.508 -0.3048)
			(stroke
				(width 0.1)
				(type default)
			)
			(layer "B.Fab")
		)
		(fp_line
			(start -0.508 -0.3048)
			(end -0.508 0.3048)
			(stroke
				(width 0.1)
				(type default)
			)
			(layer "B.Fab")
		)
		(fp_line
			(start 0.508 -0.3048)
			(end -0.508 -0.3048)
			(stroke
				(width 0.1)
				(type default)
			)
			(layer "B.Fab")
		)
		(pad "1" smd circle
			(at 0.500126 0 90)
			(size 0.635 0.635)
			(layers "B.Cu" "B.Mask" "B.Paste")
			(net "XP1R0V_FPGA_VCCINT")
		)
		(pad "2" smd circle
			(at -0.500126 0 90)
			(size 0.635 0.635)
			(layers "B.Cu" "B.Mask" "B.Paste")
			(net "SG")
		)
	)
	(footprint ""
		(layer "B.Cu")
		(at 76.784962 -15.367 -90)
		(property "Reference" "C36"
			(at -1.778 -2.169668 270)
			(unlocked yes)
			(layer "B.SilkS")
			(effects
				(font
					(size 0.7874 0.5842)
					(thickness 0.1524)
				)
				(justify mirror)
			)
		)
		(property "Value" "VAL*"
			(at -0.0762 2.067306 270)
			(unlocked yes)
			(layer "B.Fab")
			(hide yes)
			(effects
				(font
					(size 0.7874 0.5842)
					(thickness 0.1524)
				)
				(justify mirror)
			)
		)
		(property "Tolerance" "TOL*"
			(at -0.0762 3.032506 270)
			(unlocked yes)
			(layer "Cmts.User")
			(hide yes)
			(effects
				(font
					(size 0.7874 0.5842)
					(thickness 0.1524)
				)
				(justify mirror)
			)
		)
		(property "User Part Number" "PARTNUM*"
			(at -0.1016 4.023106 270)
			(unlocked yes)
			(layer "Cmts.User")
			(hide yes)
			(effects
				(font
					(size 0.7874 0.5842)
					(thickness 0.1524)
				)
				(justify mirror)
			)
		)
		(property "Device Type" "CAPACITOR-G105-0B104-CK,0.1UF,A"
			(at -0.0508 1.127506 270)
			(unlocked yes)
			(layer "B.Fab")
			(hide yes)
			(effects
				(font
					(size 0.7874 0.5842)
					(thickness 0.1524)
				)
				(justify mirror)
			)
		)
		(duplicate_pad_numbers_are_jumpers no)
		(fp_line
			(start -1.143 0.5588)
			(end -1.143 -0.5588)
			(stroke
				(width 0.1)
				(type default)
			)
			(layer "B.SilkS")
		)
		(fp_line
			(start 1.143 0.5588)
			(end -1.143 0.5588)
			(stroke
				(width 0.1)
				(type default)
			)
			(layer "B.SilkS")
		)
		(fp_line
			(start -1.143 -0.5588)
			(end 1.143 -0.5588)
			(stroke
				(width 0.1)
				(type default)
			)
			(layer "B.SilkS")
		)
		(fp_line
			(start 1.143 -0.5588)
			(end 1.143 0.5588)
			(stroke
				(width 0.1)
				(type default)
			)
			(layer "B.SilkS")
		)
		(fp_rect
			(start 1.143 0.5588)
			(end -1.143 -0.5588)
			(stroke
				(width 0)
				(type default)
			)
			(fill no)
			(layer "B.CrtYd")
		)
		(fp_line
			(start -0.508 0.3048)
			(end -0.508 -0.3048)
			(stroke
				(width 0.1)
				(type default)
			)
			(layer "B.Fab")
		)
		(fp_line
			(start 0.508 0.3048)
			(end -0.508 0.3048)
			(stroke
				(width 0.1)
				(type default)
			)
			(layer "B.Fab")
		)
		(fp_line
			(start -0.508 -0.3048)
			(end 0.508 -0.3048)
			(stroke
				(width 0.1)
				(type default)
			)
			(layer "B.Fab")
		)
		(fp_line
			(start 0.508 -0.3048)
			(end 0.508 0.3048)
			(stroke
				(width 0.1)
				(type default)
			)
			(layer "B.Fab")
		)
		(pad "1" smd rect
			(at 0.5334 0 90)
			(size 0.7112 0.6096)
			(layers "B.Cu" "B.Mask" "B.Paste")
			(net "C_CPU_RX_PCIE_MGT3_TXN")
		)
		(pad "2" smd rect
			(at -0.5334 0 90)
			(size 0.7112 0.6096)
			(layers "B.Cu" "B.Mask" "B.Paste")
			(net "CPU_RX_PCIE_MGT3_TXN")
		)
		(zone
			(layer "B.Cu")
			(hatch none 0.5)
			(connect_pads
				(clearance 0)
			)
			(min_thickness 0.25)
			(keepout
				(tracks allowed)
				(vias not_allowed)
				(pads allowed)
				(copperpour not_allowed)
				(footprints allowed)
			)
			(placement
				(enabled no)
				(sheetname "")
			)
			(fill
				(thermal_gap 0.5)
				(thermal_bridge_width 0.5)
				(island_removal_mode 0)
			)
			(polygon
				(pts
					(xy 76.480162 -15.2908) (xy 77.089762 -15.2908) (xy 77.089762 -15.4432) (xy 76.480162 -15.4432)
				)
			)
		)
	)
)
